(kicad_pcb
	(version 20260206)
	(generator "pcbnew")
	(generator_version "10.0")
	(general
		(thickness 1.6)
		(legacy_teardrops no)
	)
	(paper "A4")
	(title_block
		(title "peb — Lightning_PEB_BRD.brd")
		(comment 1 "Lightning (Wiwynn / Facebook NVMe JBOF) / footprints 920-927 of 2563")
	)
	(layers
		(0 "F.Cu" signal "TOP")
		(4 "In1.Cu" signal "L2GND")
		(6 "In2.Cu" signal "L3")
		(8 "In3.Cu" signal "L4VCC")
		(10 "In4.Cu" signal "L5VCC")
		(12 "In5.Cu" signal "L6")
		(14 "In6.Cu" signal "L7GND")
		(2 "B.Cu" signal "BOTTOM")
		(9 "F.Adhes" user "F.Adhesive")
		(11 "B.Adhes" user "B.Adhesive")
		(13 "F.Paste" user "Package Geometry/Pastemask Top")
		(15 "B.Paste" user "Package Geometry/Pastemask Bottom")
		(5 "F.SilkS" user "Ref Des/Silkscreen Top")
		(7 "B.SilkS" user "Ref Des/Silkscreen Bottom")
		(1 "F.Mask" user "Board Geometry/Soldermask Top")
		(3 "B.Mask" user "Board Geometry/Soldermask Bottom")
		(17 "Dwgs.User" user "User.Drawings")
		(19 "Cmts.User" user "User.Comments")
		(21 "Eco1.User" user "User.Eco1")
		(23 "Eco2.User" user "User.Eco2")
		(25 "Edge.Cuts" user "Board Geometry/Outline")
		(27 "Margin" user)
		(31 "F.CrtYd" user "Package Geometry/Place Bound Top")
		(29 "B.CrtYd" user "Package Geometry/Place Bound Bottom")
		(35 "F.Fab" user "Ref Des/Assembly Top")
		(33 "B.Fab" user "Ref Des/Assembly Bottom")
	)
	(footprint ""
		(layer "F.Cu")
		(at 20.955 -135.7122 90)
		(property "Reference" "R289"
			(at 0 0 90)
			(layer "F.SilkS")
			(hide yes)
			(effects
				(font
					(size 1.27 1.27)
				)
			)
		)
		(property "Value" "0R2J-2-GP"
			(at 0.064008 -3.993896 90)
			(unlocked yes)
			(layer "F.Fab")
			(hide yes)
			(effects
				(font
					(size 1.016 1.016)
					(thickness 0.1524)
				)
			)
		)
		(property "Device Type" "R402H16"
			(at 0.064008 -5.517896 90)
			(unlocked yes)
			(layer "F.Fab")
			(hide yes)
			(effects
				(font
					(size 1.016 1.016)
					(thickness 0.1524)
				)
			)
		)
		(duplicate_pad_numbers_are_jumpers no)
		(fp_line
			(start 0.508 -0.9398)
			(end -0.508 -0.9398)
			(stroke
				(width 0.1524)
				(type default)
			)
			(layer "F.SilkS")
		)
		(fp_line
			(start -0.508 -0.9398)
			(end -0.508 0.9398)
			(stroke
				(width 0.1524)
				(type default)
			)
			(layer "F.SilkS")
		)
		(fp_rect
			(start -0.508 0.9398)
			(end 0.508 -0.9398)
			(stroke
				(width 0)
				(type default)
			)
			(fill no)
			(layer "F.CrtYd")
		)
		(fp_rect
			(start -0.508 0.9398)
			(end 0.508 -0.9398)
			(stroke
				(width 0)
				(type default)
			)
			(fill no)
			(layer "F.Fab")
		)
		(pad "1" smd custom
			(at 0 -0.4445 90)
			(size 0.1397 0.1397)
			(layers "F.Cu" "F.Mask" "F.Paste")
			(net "BMC_INT_N")
			(options
				(clearance outline)
				(anchor circle)
			)
			(primitives
				(gr_poly
					(pts
						(arc
							(start -0.1778 -0.2794)
							(mid -0.249642 -0.249642)
							(end -0.2794 -0.1778)
						)
						(arc
							(start -0.2794 0.1778)
							(mid -0.249642 0.249642)
							(end -0.1778 0.2794)
						)
						(arc
							(start 0.1778 0.2794)
							(mid 0.249642 0.249642)
							(end 0.2794 0.1778)
						)
						(arc
							(start 0.2794 -0.1778)
							(mid 0.249642 -0.249642)
							(end 0.1778 -0.2794)
						)
					)
					(width 0)
					(fill yes)
				)
			)
		)
		(pad "2" smd custom
			(at 0 0.4445 90)
			(size 0.1397 0.1397)
			(layers "F.Cu" "F.Mask" "F.Paste")
			(net "GPIOR4_BMC_INT_N_R")
			(options
				(clearance outline)
				(anchor circle)
			)
			(primitives
				(gr_poly
					(pts
						(arc
							(start -0.1778 -0.2794)
							(mid -0.249642 -0.249642)
							(end -0.2794 -0.1778)
						)
						(arc
							(start -0.2794 0.1778)
							(mid -0.249642 0.249642)
							(end -0.1778 0.2794)
						)
						(arc
							(start 0.1778 0.2794)
							(mid 0.249642 0.249642)
							(end 0.2794 0.1778)
						)
						(arc
							(start 0.2794 -0.1778)
							(mid 0.249642 -0.249642)
							(end 0.1778 -0.2794)
						)
					)
					(width 0)
					(fill yes)
				)
			)
		)
	)
	(footprint ""
		(layer "F.Cu")
		(at 175.992028 -212.420454 180)
		(property "Reference" "C128"
			(at 0 0 180)
			(layer "F.SilkS")
			(hide yes)
			(effects
				(font
					(size 1.27 1.27)
				)
			)
		)
		(property "Value" "SCD22U10V2KX-1GP"
			(at 1.1811 -2.7051 180)
			(unlocked yes)
			(layer "F.Fab")
			(hide yes)
			(effects
				(font
					(size 1.016 1.016)
					(thickness 0.1524)
				)
			)
		)
		(property "Device Type" "C402H22"
			(at 1.1811 -4.2291 180)
			(unlocked yes)
			(layer "F.Fab")
			(hide yes)
			(effects
				(font
					(size 1.016 1.016)
					(thickness 0.1524)
				)
			)
		)
		(duplicate_pad_numbers_are_jumpers no)
		(fp_rect
			(start -0.4318 0.9525)
			(end 0.4318 -0.9525)
			(stroke
				(width 0)
				(type default)
			)
			(fill no)
			(layer "F.CrtYd")
		)
		(fp_rect
			(start -0.4318 0.9525)
			(end 0.4318 -0.9525)
			(stroke
				(width 0)
				(type default)
			)
			(fill no)
			(layer "F.Fab")
		)
		(pad "1" smd custom
			(at 0 -0.4445 180)
			(size 0.1524 0.1524)
			(layers "F.Cu" "F.Mask" "F.Paste")
			(net "PCIE_TX_CAP_P48")
			(options
				(clearance outline)
				(anchor circle)
			)
			(primitives
				(gr_poly
					(pts
						(arc
							(start 0.3048 -0.2032)
							(mid 0.275042 -0.275042)
							(end 0.2032 -0.3048)
						)
						(arc
							(start -0.2032 -0.3048)
							(mid -0.275042 -0.275042)
							(end -0.3048 -0.2032)
						)
						(arc
							(start -0.3048 0.2032)
							(mid -0.275042 0.275042)
							(end -0.2032 0.3048)
						)
						(arc
							(start 0.2032 0.3048)
							(mid 0.275042 0.275042)
							(end 0.3048 0.2032)
						)
					)
					(width 0)
					(fill yes)
				)
			)
		)
		(pad "2" smd custom
			(at 0 0.4445 180)
			(size 0.1524 0.1524)
			(layers "F.Cu" "F.Mask" "F.Paste")
			(net "PCIE_TX_P48")
			(options
				(clearance outline)
				(anchor circle)
			)
			(primitives
				(gr_poly
					(pts
						(arc
							(start 0.3048 -0.2032)
							(mid 0.275042 -0.275042)
							(end 0.2032 -0.3048)
						)
						(arc
							(start -0.2032 -0.3048)
							(mid -0.275042 -0.275042)
							(end -0.3048 -0.2032)
						)
						(arc
							(start -0.3048 0.2032)
							(mid -0.275042 0.275042)
							(end -0.2032 0.3048)
						)
						(arc
							(start 0.2032 0.3048)
							(mid 0.275042 0.275042)
							(end 0.3048 0.2032)
						)
					)
					(width 0)
					(fill yes)
				)
			)
		)
	)
	(footprint ""
		(layer "F.Cu")
		(at 273.939 -14.478 90)
		(property "Reference" "C7"
			(at 0 0 90)
			(layer "F.SilkS")
			(hide yes)
			(effects
				(font
					(size 1.27 1.27)
				)
			)
		)
		(property "Value" "SCD22U10V2KX-1GP"
			(at 1.1811 -2.7051 90)
			(unlocked yes)
			(layer "F.Fab")
			(hide yes)
			(effects
				(font
					(size 1.016 1.016)
					(thickness 0.1524)
				)
			)
		)
		(property "Device Type" "C402H22"
			(at 1.1811 -4.2291 90)
			(unlocked yes)
			(layer "F.Fab")
			(hide yes)
			(effects
				(font
					(size 1.016 1.016)
					(thickness 0.1524)
				)
			)
		)
		(duplicate_pad_numbers_are_jumpers no)
		(fp_rect
			(start -0.4318 0.9525)
			(end 0.4318 -0.9525)
			(stroke
				(width 0)
				(type default)
			)
			(fill no)
			(layer "F.CrtYd")
		)
		(fp_rect
			(start -0.4318 0.9525)
			(end 0.4318 -0.9525)
			(stroke
				(width 0)
				(type default)
			)
			(fill no)
			(layer "F.Fab")
		)
		(pad "1" smd custom
			(at 0 -0.4445 90)
			(size 0.1524 0.1524)
			(layers "F.Cu" "F.Mask" "F.Paste")
			(net "PCIE_TX_CAP_P1")
			(options
				(clearance outline)
				(anchor circle)
			)
			(primitives
				(gr_poly
					(pts
						(arc
							(start 0.3048 -0.2032)
							(mid 0.275042 -0.275042)
							(end 0.2032 -0.3048)
						)
						(arc
							(start -0.2032 -0.3048)
							(mid -0.275042 -0.275042)
							(end -0.3048 -0.2032)
						)
						(arc
							(start -0.3048 0.2032)
							(mid -0.275042 0.275042)
							(end -0.2032 0.3048)
						)
						(arc
							(start 0.2032 0.3048)
							(mid 0.275042 0.275042)
							(end 0.3048 0.2032)
						)
					)
					(width 0)
					(fill yes)
				)
			)
		)
		(pad "2" smd custom
			(at 0 0.4445 90)
			(size 0.1524 0.1524)
			(layers "F.Cu" "F.Mask" "F.Paste")
			(net "PCIE_TX_P1")
			(options
				(clearance outline)
				(anchor circle)
			)
			(primitives
				(gr_poly
					(pts
						(arc
							(start 0.3048 -0.2032)
							(mid 0.275042 -0.275042)
							(end 0.2032 -0.3048)
						)
						(arc
							(start -0.2032 -0.3048)
							(mid -0.275042 -0.275042)
							(end -0.3048 -0.2032)
						)
						(arc
							(start -0.3048 0.2032)
							(mid -0.275042 0.275042)
							(end -0.2032 0.3048)
						)
						(arc
							(start 0.2032 0.3048)
							(mid 0.275042 0.275042)
							(end 0.3048 0.2032)
						)
					)
					(width 0)
					(fill yes)
				)
			)
		)
	)
	(footprint ""
		(layer "F.Cu")
		(at 185.600086 -17.500092 -90)
		(property "Reference" "LED19"
			(at 0 0 270)
			(layer "F.SilkS")
			(hide yes)
			(effects
				(font
					(size 1.27 1.27)
				)
			)
		)
		(property "Value" "LED-YG-51-GP"
			(at -2.6924 -1.4224 270)
			(unlocked yes)
			(layer "F.Fab")
			(hide yes)
			(effects
				(font
					(size 1.016 1.016)
					(thickness 0.1524)
				)
			)
		)
		(property "Device Type" "LED1608AKH40"
			(at -2.6924 -2.9464 270)
			(unlocked yes)
			(layer "F.Fab")
			(hide yes)
			(effects
				(font
					(size 1.016 1.016)
					(thickness 0.1524)
				)
			)
		)
		(duplicate_pad_numbers_are_jumpers no)
		(fp_line
			(start -0.7493 1.651)
			(end -0.7493 1.1811)
			(stroke
				(width 0.3302)
				(type default)
			)
			(layer "F.SilkS")
		)
		(fp_line
			(start 0.7493 1.651)
			(end 0.7493 1.1811)
			(stroke
				(width 0.3302)
				(type default)
			)
			(layer "F.SilkS")
		)
		(fp_line
			(start -0.5969 1.5494)
			(end 0.5842 1.5494)
			(stroke
				(width 0.508)
				(type default)
			)
			(layer "F.SilkS")
		)
		(fp_line
			(start -0.6604 1.3716)
			(end -0.6604 -1.3716)
			(stroke
				(width 0.1524)
				(type default)
			)
			(layer "F.SilkS")
		)
		(fp_line
			(start 0.6604 1.3716)
			(end -0.6604 1.3716)
			(stroke
				(width 0.1524)
				(type default)
			)
			(layer "F.SilkS")
		)
		(fp_line
			(start -0.6604 -1.3716)
			(end 0.6604 -1.3716)
			(stroke
				(width 0.1524)
				(type default)
			)
			(layer "F.SilkS")
		)
		(fp_line
			(start 0.6604 -1.3716)
			(end 0.6604 1.3716)
			(stroke
				(width 0.1524)
				(type default)
			)
			(layer "F.SilkS")
		)
		(fp_rect
			(start -0.6223 1.3335)
			(end 0.6223 -1.3335)
			(stroke
				(width 0)
				(type default)
			)
			(fill no)
			(layer "F.CrtYd")
		)
		(fp_rect
			(start -0.6223 1.3335)
			(end 0.6223 -1.3335)
			(stroke
				(width 0)
				(type default)
			)
			(fill no)
			(layer "F.Fab")
		)
		(pad "A" smd custom
			(at 0 -0.762 270)
			(size 0.2159 0.2159)
			(layers "F.Cu" "F.Mask" "F.Paste")
			(net "LED_R_10")
			(options
				(clearance outline)
				(anchor circle)
			)
			(primitives
				(gr_poly
					(pts
						(arc
							(start -0.3302 -0.4318)
							(mid -0.402042 -0.402042)
							(end -0.4318 -0.3302)
						)
						(arc
							(start -0.4318 0.3302)
							(mid -0.402042 0.402042)
							(end -0.3302 0.4318)
						)
						(arc
							(start 0.3302 0.4318)
							(mid 0.402042 0.402042)
							(end 0.4318 0.3302)
						)
						(arc
							(start 0.4318 -0.3302)
							(mid 0.402042 -0.402042)
							(end 0.3302 -0.4318)
						)
					)
					(width 0)
					(fill yes)
				)
			)
		)
		(pad "K" smd custom
			(at 0 0.762 270)
			(size 0.2159 0.2159)
			(layers "F.Cu" "F.Mask" "F.Paste")
			(net "LED_Q_10")
			(options
				(clearance outline)
				(anchor circle)
			)
			(primitives
				(gr_poly
					(pts
						(arc
							(start -0.3302 -0.4318)
							(mid -0.402042 -0.402042)
							(end -0.4318 -0.3302)
						)
						(arc
							(start -0.4318 0.3302)
							(mid -0.402042 0.402042)
							(end -0.3302 0.4318)
						)
						(arc
							(start 0.3302 0.4318)
							(mid 0.402042 0.402042)
							(end 0.4318 0.3302)
						)
						(arc
							(start 0.4318 -0.3302)
							(mid 0.402042 -0.402042)
							(end 0.3302 -0.4318)
						)
					)
					(width 0)
					(fill yes)
				)
			)
		)
	)
	(footprint ""
		(layer "F.Cu")
		(at 345.694 -48.768 180)
		(property "Reference" "PL8"
			(at 0 0 180)
			(layer "F.SilkS")
			(hide yes)
			(effects
				(font
					(size 1.27 1.27)
				)
			)
		)
		(property "Value" "BLM41PG600-GP"
			(at -3.690874 -7.441184 180)
			(unlocked yes)
			(layer "F.Fab")
			(hide yes)
			(effects
				(font
					(size 1.016 1.016)
					(thickness 0.1524)
				)
			)
		)
		(property "Device Type" "L451616H71"
			(at -3.690874 -5.917184 180)
			(unlocked yes)
			(layer "F.Fab")
			(hide yes)
			(effects
				(font
					(size 1.016 1.016)
					(thickness 0.1524)
				)
			)
		)
		(duplicate_pad_numbers_are_jumpers no)
		(fp_line
			(start 2.8702 1.2954)
			(end 2.8702 -1.2954)
			(stroke
				(width 0.1524)
				(type default)
			)
			(layer "F.SilkS")
		)
		(fp_line
			(start 2.8702 1.2954)
			(end 2.8702 -1.2954)
			(stroke
				(width 0.1524)
				(type default)
			)
			(layer "F.SilkS")
		)
		(fp_line
			(start 2.8702 -1.2954)
			(end -2.8702 -1.2954)
			(stroke
				(width 0.1524)
				(type default)
			)
			(layer "F.SilkS")
		)
		(fp_line
			(start 2.8702 -1.2954)
			(end -2.8702 -1.2954)
			(stroke
				(width 0.1524)
				(type default)
			)
			(layer "F.SilkS")
		)
		(fp_line
			(start -2.8702 1.2954)
			(end 2.8702 1.2954)
			(stroke
				(width 0.1524)
				(type default)
			)
			(layer "F.SilkS")
		)
		(fp_line
			(start -2.8702 1.2954)
			(end 2.8702 1.2954)
			(stroke
				(width 0.1524)
				(type default)
			)
			(layer "F.SilkS")
		)
		(fp_line
			(start -2.8702 -1.2954)
			(end -2.8702 1.2954)
			(stroke
				(width 0.1524)
				(type default)
			)
			(layer "F.SilkS")
		)
		(fp_line
			(start -2.8702 -1.2954)
			(end -2.8702 1.2954)
			(stroke
				(width 0.1524)
				(type default)
			)
			(layer "F.SilkS")
		)
		(fp_poly
			(pts
				(xy -2.8702 1.2954) (xy 2.8702 1.2954) (xy 2.8702 -1.2954) (xy -2.8702 -1.2954)
			)
			(stroke
				(width 0)
				(type default)
			)
			(fill no)
			(layer "F.CrtYd")
		)
		(fp_poly
			(pts
				(xy -2.8702 1.2954) (xy 2.8702 1.2954) (xy 2.8702 -1.2954) (xy -2.8702 -1.2954)
			)
			(stroke
				(width 0)
				(type default)
			)
			(fill no)
			(layer "F.Fab")
		)
		(pad "1" smd rect
			(at -1.9685 0 180)
			(size 1.3716 1.8796)
			(layers "F.Cu" "F.Mask" "F.Paste")
			(net "P12V")
		)
		(pad "2" smd rect
			(at 1.9685 0 180)
			(size 1.3716 1.8796)
			(layers "F.Cu" "F.Mask" "F.Paste")
			(net "P0V9_E_VIN")
		)
	)
	(footprint ""
		(layer "F.Cu")
		(at 130.195066 -208.8769 180)
		(property "Reference" "R7941"
			(at 0 0 180)
			(layer "F.SilkS")
			(hide yes)
			(effects
				(font
					(size 1.27 1.27)
				)
			)
		)
		(property "Value" "0R2J-2-GP"
			(at 0.064008 -3.993896 180)
			(unlocked yes)
			(layer "F.Fab")
			(hide yes)
			(effects
				(font
					(size 1.016 1.016)
					(thickness 0.1524)
				)
			)
		)
		(property "Device Type" "R402H16"
			(at 0.064008 -5.517896 180)
			(unlocked yes)
			(layer "F.Fab")
			(hide yes)
			(effects
				(font
					(size 1.016 1.016)
					(thickness 0.1524)
				)
			)
		)
		(duplicate_pad_numbers_are_jumpers no)
		(fp_line
			(start 0.508 -0.9398)
			(end -0.508 -0.9398)
			(stroke
				(width 0.1524)
				(type default)
			)
			(layer "F.SilkS")
		)
		(fp_line
			(start -0.508 -0.9398)
			(end -0.508 0.9398)
			(stroke
				(width 0.1524)
				(type default)
			)
			(layer "F.SilkS")
		)
		(fp_rect
			(start -0.508 0.9398)
			(end 0.508 -0.9398)
			(stroke
				(width 0)
				(type default)
			)
			(fill no)
			(layer "F.CrtYd")
		)
		(fp_rect
			(start -0.508 0.9398)
			(end 0.508 -0.9398)
			(stroke
				(width 0)
				(type default)
			)
			(fill no)
			(layer "F.Fab")
		)
		(pad "1" smd custom
			(at 0 -0.4445 180)
			(size 0.1397 0.1397)
			(layers "F.Cu" "F.Mask" "F.Paste")
			(net "SSD_ATNLED#7")
			(options
				(clearance outline)
				(anchor circle)
			)
			(primitives
				(gr_poly
					(pts
						(arc
							(start -0.1778 -0.2794)
							(mid -0.249642 -0.249642)
							(end -0.2794 -0.1778)
						)
						(arc
							(start -0.2794 0.1778)
							(mid -0.249642 0.249642)
							(end -0.1778 0.2794)
						)
						(arc
							(start 0.1778 0.2794)
							(mid 0.249642 0.249642)
							(end 0.2794 0.1778)
						)
						(arc
							(start 0.2794 -0.1778)
							(mid 0.249642 -0.249642)
							(end 0.1778 -0.2794)
						)
					)
					(width 0)
					(fill yes)
				)
			)
		)
		(pad "2" smd custom
			(at 0 0.4445 180)
			(size 0.1397 0.1397)
			(layers "F.Cu" "F.Mask" "F.Paste")
			(net "SSD_ATNLED#7_R")
			(options
				(clearance outline)
				(anchor circle)
			)
			(primitives
				(gr_poly
					(pts
						(arc
							(start -0.1778 -0.2794)
							(mid -0.249642 -0.249642)
							(end -0.2794 -0.1778)
						)
						(arc
							(start -0.2794 0.1778)
							(mid -0.249642 0.249642)
							(end -0.1778 0.2794)
						)
						(arc
							(start 0.1778 0.2794)
							(mid 0.249642 0.249642)
							(end 0.2794 0.1778)
						)
						(arc
							(start 0.2794 -0.1778)
							(mid 0.249642 -0.249642)
							(end 0.1778 -0.2794)
						)
					)
					(width 0)
					(fill yes)
				)
			)
		)
	)
	(footprint ""
		(layer "F.Cu")
		(at 35.28822 -118.27764)
		(property "Reference" "TP233"
			(at 0 0 0)
			(layer "F.SilkS")
			(hide yes)
			(effects
				(font
					(size 1.27 1.27)
				)
			)
		)
		(property "Value" "TPAD28-2-GP"
			(at -0.0127 -1.6637 0)
			(unlocked yes)
			(layer "F.Fab")
			(hide yes)
			(effects
				(font
					(size 1.016 1.016)
					(thickness 0.1524)
				)
			)
		)
		(property "Device Type" "TPAD28"
			(at -0.0127 -3.1877 0)
			(unlocked yes)
			(layer "F.Fab")
			(hide yes)
			(effects
				(font
					(size 1.016 1.016)
					(thickness 0.1524)
				)
			)
		)
		(duplicate_pad_numbers_are_jumpers no)
		(fp_poly
			(pts
				(arc
					(start 0.3556 0)
					(mid -0.3556 0)
					(end 0.3556 0)
				)
			)
			(stroke
				(width 0)
				(type default)
			)
			(fill no)
			(layer "F.CrtYd")
		)
		(fp_poly
			(pts
				(arc
					(start 0.6096 0)
					(mid -0.6096 0)
					(end 0.6096 0)
				)
			)
			(stroke
				(width 0)
				(type default)
			)
			(fill no)
			(layer "F.Fab")
		)
		(pad "1" smd circle
			(at 0 0)
			(size 0.7112 0.7112)
			(layers "F.Cu" "F.Mask" "F.Paste")
			(net "TP_GPIOE3")
		)
	)
	(footprint ""
		(layer "F.Cu")
		(at 88.9 -45.0342)
		(property "Reference" "PG9"
			(at 0 0 0)
			(layer "F.SilkS")
			(hide yes)
			(effects
				(font
					(size 1.27 1.27)
				)
			)
		)
		(property "Value" "GAP-CLOSE-PWR-3-GP"
			(at 0.0254 -6.5786 0)
			(unlocked yes)
			(layer "F.Fab")
			(hide yes)
			(effects
				(font
					(size 1.016 1.016)
					(thickness 0.1524)
				)
			)
		)
		(property "Device Type" "GAP-CLOSE-PWR-3"
			(at 0.0254 -8.255 0)
			(unlocked yes)
			(layer "F.Fab")
			(hide yes)
			(effects
				(font
					(size 1.016 1.016)
					(thickness 0.1524)
				)
			)
		)
		(duplicate_pad_numbers_are_jumpers no)
		(fp_rect
			(start -0.7112 0.4572)
			(end 0.7112 -0.4572)
			(stroke
				(width 0)
				(type default)
			)
			(fill no)
			(layer "F.CrtYd")
		)
		(fp_poly
			(pts
				(xy -0.7112 -0.4572) (xy 0.7112 -0.4572) (xy 0.7112 0.4572) (xy -0.7112 0.4572)
			)
			(stroke
				(width 0)
				(type default)
			)
			(fill no)
			(layer "F.Fab")
		)
		(pad "1" smd rect
			(at -0.3048 0)
			(size 0.6604 0.762)
			(layers "F.Cu" "F.Mask" "F.Paste")
			(net "P3V3_PWR")
		)
		(pad "2" smd rect
			(at 0.3048 0)
			(size 0.6604 0.762)
			(layers "F.Cu" "F.Mask" "F.Paste")
			(net "P3V3_STBY")
		)
	)
)
